# SCM (Grand Teton) — schematic netlist excerpt (pin names and nets, part order shuffled) for the footprints in the layout excerpt that follows; sources: Cadence DE-HDL packaged netlist, KiCad conversion of 12092022_DA0F0TMDCD0_F0T_Management_Board_D_brd_V3_OCP.brd

R133  Q_RES  33.2 1% CHIP  pkg 0402LF  page 12 : A = SMB_BMC_MM1_R_SDA ; B = SMB_BMC_MM1_SDA
C53  Q_CAP  1UF 25V 10% X6S  pkg C0402  page 17 : A = P3V3_P1V8_I2C_I3C ; B = GND

(kicad_pcb
	(version 20260206)
	(generator "pcbnew")
	(generator_version "10.0")
	(general
		(thickness 1.6)
		(legacy_teardrops no)
	)
	(paper "A4")
	(title_block
		(title "12092022_DA0F0TMDCD0_F0T_Management_Board_D_brd_V3_OCP.brd")
		(comment 1 "Grand Teton / footprints 260-261 of 1440")
	)
	(layers
		(0 "F.Cu" signal "TOP")
		(4 "In1.Cu" signal "GND")
		(6 "In2.Cu" signal "IN1")
		(8 "In3.Cu" signal "GND1")
		(10 "In4.Cu" signal "IN2")
		(12 "In5.Cu" signal "VCC")
		(14 "In6.Cu" signal "VCC1")
		(16 "In7.Cu" signal "IN3")
		(18 "In8.Cu" signal "GND2")
		(20 "In9.Cu" signal "IN4")
		(22 "In10.Cu" signal "GND3")
		(2 "B.Cu" signal "BOTTOM")
		(9 "F.Adhes" user "F.Adhesive")
		(11 "B.Adhes" user "B.Adhesive")
		(13 "F.Paste" user "Package Geometry/Pastemask Top")
		(15 "B.Paste" user "Package Geometry/Pastemask Bottom")
		(5 "F.SilkS" user "Ref Des/Silkscreen Top")
		(7 "B.SilkS" user "Ref Des/Silkscreen Bottom")
		(1 "F.Mask" user "Board Geometry/Soldermask Top")
		(3 "B.Mask" user "Board Geometry/Soldermask Bottom")
		(17 "Dwgs.User" user "User.Drawings")
		(19 "Cmts.User" user "User.Comments")
		(21 "Eco1.User" user "User.Eco1")
		(23 "Eco2.User" user "User.Eco2")
		(25 "Edge.Cuts" user "Board Geometry/Outline")
		(27 "Margin" user)
		(31 "F.CrtYd" user "Package Geometry/Place Bound Top")
		(29 "B.CrtYd" user "Package Geometry/Place Bound Bottom")
		(35 "F.Fab" user "Ref Des/Assembly Top")
		(33 "B.Fab" user "Ref Des/Assembly Bottom")
	)
	(footprint ""
		(layer "F.Cu")
		(at 48.768 -34.6456 -90)
		(property "Reference" "R133"
			(at 0 0 270)
			(layer "F.SilkS")
			(hide yes)
			(effects
				(font
					(size 1.27 1.27)
				)
			)
		)
		(property "Value" ""
			(at 0 0 270)
			(layer "F.Fab")
			(effects
				(font
					(size 1.27 1.27)
				)
			)
		)
		(duplicate_pad_numbers_are_jumpers no)
		(fp_line
			(start -0.7874 0.4064)
			(end -0.7874 -0.4064)
			(stroke
				(width 0.1524)
				(type default)
			)
			(layer "F.SilkS")
		)
		(fp_line
			(start 0.7874 0.4064)
			(end -0.7874 0.4064)
			(stroke
				(width 0.1524)
				(type default)
			)
			(layer "F.SilkS")
		)
		(fp_line
			(start -0.7874 -0.4064)
			(end 0.7874 -0.4064)
			(stroke
				(width 0.1524)
				(type default)
			)
			(layer "F.SilkS")
		)
		(fp_line
			(start 0.7874 -0.4064)
			(end 0.7874 0.4064)
			(stroke
				(width 0.1524)
				(type default)
			)
			(layer "F.SilkS")
		)
		(fp_line
			(start -0.67945 0.3048)
			(end -0.67945 -0.305054)
			(stroke
				(width 0.1)
				(type default)
			)
			(layer "F.Fab")
		)
		(fp_line
			(start -0.12065 0.3048)
			(end -0.67945 0.3048)
			(stroke
				(width 0.1)
				(type default)
			)
			(layer "F.Fab")
		)
		(fp_line
			(start 0.120396 0.3048)
			(end 0.120396 0.2794)
			(stroke
				(width 0.1)
				(type default)
			)
			(layer "F.Fab")
		)
		(fp_line
			(start 0.67945 0.3048)
			(end 0.120396 0.3048)
			(stroke
				(width 0.1)
				(type default)
			)
			(layer "F.Fab")
		)
		(fp_line
			(start -0.12065 0.2794)
			(end -0.12065 0.3048)
			(stroke
				(width 0.1)
				(type default)
			)
			(layer "F.Fab")
		)
		(fp_line
			(start 0.120396 0.2794)
			(end -0.12065 0.2794)
			(stroke
				(width 0.1)
				(type default)
			)
			(layer "F.Fab")
		)
		(fp_line
			(start -0.12065 -0.2794)
			(end 0.12065 -0.2794)
			(stroke
				(width 0.1)
				(type default)
			)
			(layer "F.Fab")
		)
		(fp_line
			(start 0.12065 -0.2794)
			(end 0.12065 -0.3048)
			(stroke
				(width 0.1)
				(type default)
			)
			(layer "F.Fab")
		)
		(fp_line
			(start 0.12065 -0.3048)
			(end 0.67945 -0.3048)
			(stroke
				(width 0.1)
				(type default)
			)
			(layer "F.Fab")
		)
		(fp_line
			(start 0.67945 -0.3048)
			(end 0.67945 0.3048)
			(stroke
				(width 0.1)
				(type default)
			)
			(layer "F.Fab")
		)
		(fp_line
			(start -0.67945 -0.305054)
			(end -0.12065 -0.305054)
			(stroke
				(width 0.1)
				(type default)
			)
			(layer "F.Fab")
		)
		(fp_line
			(start -0.12065 -0.305054)
			(end -0.12065 -0.2794)
			(stroke
				(width 0.1)
				(type default)
			)
			(layer "F.Fab")
		)
		(pad "1" smd circle
			(at -0.40005 0 270)
			(size 0 0)
			(layers "F.Cu" "F.Mask" "F.Paste")
			(net "SMB_BMC_MM1_R_SDA")
		)
		(pad "2" smd circle
			(at 0.40005 0 270)
			(size 0 0)
			(layers "F.Cu" "F.Mask" "F.Paste")
			(net "SMB_BMC_MM1_SDA")
		)
	)
	(footprint ""
		(layer "F.Cu")
		(at 35.941 -36.068 90)
		(property "Reference" "C53"
			(at 0 0 90)
			(layer "F.SilkS")
			(hide yes)
			(effects
				(font
					(size 1.27 1.27)
				)
			)
		)
		(property "Value" ""
			(at 0 0 90)
			(layer "F.Fab")
			(effects
				(font
					(size 1.27 1.27)
				)
			)
		)
		(duplicate_pad_numbers_are_jumpers no)
		(fp_line
			(start 0.7874 -0.4064)
			(end 0.7874 0.4064)
			(stroke
				(width 0.1524)
				(type default)
			)
			(layer "F.SilkS")
		)
		(fp_line
			(start -0.7874 -0.4064)
			(end 0.7874 -0.4064)
			(stroke
				(width 0.1524)
				(type default)
			)
			(layer "F.SilkS")
		)
		(fp_line
			(start 0.7874 0.4064)
			(end -0.7874 0.4064)
			(stroke
				(width 0.1524)
				(type default)
			)
			(layer "F.SilkS")
		)
		(fp_line
			(start -0.7874 0.4064)
			(end -0.7874 -0.4064)
			(stroke
				(width 0.1524)
				(type default)
			)
			(layer "F.SilkS")
		)
		(fp_line
			(start -0.12065 -0.305054)
			(end -0.12065 -0.2794)
			(stroke
				(width 0.1)
				(type default)
			)
			(layer "F.Fab")
		)
		(fp_line
			(start -0.67945 -0.305054)
			(end -0.12065 -0.305054)
			(stroke
				(width 0.1)
				(type default)
			)
			(layer "F.Fab")
		)
		(fp_line
			(start 0.67945 -0.3048)
			(end 0.67945 0.3048)
			(stroke
				(width 0.1)
				(type default)
			)
			(layer "F.Fab")
		)
		(fp_line
			(start 0.12065 -0.3048)
			(end 0.67945 -0.3048)
			(stroke
				(width 0.1)
				(type default)
			)
			(layer "F.Fab")
		)
		(fp_line
			(start 0.12065 -0.2794)
			(end 0.12065 -0.3048)
			(stroke
				(width 0.1)
				(type default)
			)
			(layer "F.Fab")
		)
		(fp_line
			(start -0.12065 -0.2794)
			(end 0.12065 -0.2794)
			(stroke
				(width 0.1)
				(type default)
			)
			(layer "F.Fab")
		)
		(fp_line
			(start 0.120396 0.2794)
			(end -0.12065 0.2794)
			(stroke
				(width 0.1)
				(type default)
			)
			(layer "F.Fab")
		)
		(fp_line
			(start -0.12065 0.2794)
			(end -0.12065 0.3048)
			(stroke
				(width 0.1)
				(type default)
			)
			(layer "F.Fab")
		)
		(fp_line
			(start 0.67945 0.3048)
			(end 0.120396 0.3048)
			(stroke
				(width 0.1)
				(type default)
			)
			(layer "F.Fab")
		)
		(fp_line
			(start 0.120396 0.3048)
			(end 0.120396 0.2794)
			(stroke
				(width 0.1)
				(type default)
			)
			(layer "F.Fab")
		)
		(fp_line
			(start -0.12065 0.3048)
			(end -0.67945 0.3048)
			(stroke
				(width 0.1)
				(type default)
			)
			(layer "F.Fab")
		)
		(fp_line
			(start -0.67945 0.3048)
			(end -0.67945 -0.305054)
			(stroke
				(width 0.1)
				(type default)
			)
			(layer "F.Fab")
		)
		(pad "1" smd circle
			(at -0.40005 0 90)
			(size 0 0)
			(layers "F.Cu" "F.Mask" "F.Paste")
			(net "P3V3_P1V8_I2C_I3C")
		)
		(pad "2" smd circle
			(at 0.40005 0 90)
			(size 0 0)
			(layers "F.Cu" "F.Mask" "F.Paste")
			(net "GND")
		)
	)
)
